(kicad_pcb
	(version 20260206)
	(generator "pcbnew")
	(generator_version "10.0")
	(general
		(thickness 1.6)
		(legacy_teardrops no)
	)
	(paper "A4")
	(title_block
		(title "Bryce Canyon_F.DPB_16315-1-OCP.brd")
		(comment 1 "Bryce Canyon / footprints 135-141 of 2223")
	)
	(layers
		(0 "F.Cu" signal "TOP")
		(4 "In1.Cu" signal "L2GND")
		(6 "In2.Cu" signal "L3")
		(8 "In3.Cu" signal "L4GND")
		(10 "In4.Cu" signal "L5")
		(12 "In5.Cu" signal "L6VCC")
		(14 "In6.Cu" signal "L7VCC")
		(16 "In7.Cu" signal "L8")
		(18 "In8.Cu" signal "L9GND")
		(20 "In9.Cu" signal "L10")
		(22 "In10.Cu" signal "L11GND")
		(2 "B.Cu" signal "BOTTOM")
		(9 "F.Adhes" user "F.Adhesive")
		(11 "B.Adhes" user "B.Adhesive")
		(13 "F.Paste" user "Package Geometry/Pastemask Top")
		(15 "B.Paste" user "Package Geometry/Pastemask Bottom")
		(5 "F.SilkS" user "Ref Des/Silkscreen Top")
		(7 "B.SilkS" user "Ref Des/Silkscreen Bottom")
		(1 "F.Mask" user "Board Geometry/Soldermask Top")
		(3 "B.Mask" user "Board Geometry/Soldermask Bottom")
		(17 "Dwgs.User" user "User.Drawings")
		(19 "Cmts.User" user "User.Comments")
		(21 "Eco1.User" user "User.Eco1")
		(23 "Eco2.User" user "User.Eco2")
		(25 "Edge.Cuts" user "Board Geometry/Outline")
		(27 "Margin" user)
		(31 "F.CrtYd" user "Package Geometry/Place Bound Top")
		(29 "B.CrtYd" user "Package Geometry/Place Bound Bottom")
		(35 "F.Fab" user "Ref Des/Assembly Top")
		(33 "B.Fab" user "Ref Des/Assembly Bottom")
	)
	(footprint ""
		(layer "F.Cu")
		(at 270.82115 11.6078)
		(property "Reference" "R138"
			(at 0 0 0)
			(layer "F.SilkS")
			(hide yes)
			(effects
				(font
					(size 1.27 1.27)
				)
			)
		)
		(property "Value" "4K7R2F-GP"
			(at 0.064008 -3.993896 0)
			(unlocked yes)
			(layer "F.Fab")
			(hide yes)
			(effects
				(font
					(size 1.016 1.016)
					(thickness 0.1524)
				)
			)
		)
		(property "Device Type" "R402H16"
			(at 0.064008 -5.517896 0)
			(unlocked yes)
			(layer "F.Fab")
			(hide yes)
			(effects
				(font
					(size 1.016 1.016)
					(thickness 0.1524)
				)
			)
		)
		(duplicate_pad_numbers_are_jumpers no)
		(fp_line
			(start -0.508 -0.9398)
			(end -0.508 0.9398)
			(stroke
				(width 0.1524)
				(type default)
			)
			(layer "F.SilkS")
		)
		(fp_line
			(start 0.508 -0.9398)
			(end -0.508 -0.9398)
			(stroke
				(width 0.1524)
				(type default)
			)
			(layer "F.SilkS")
		)
		(fp_rect
			(start -0.508 0.9398)
			(end 0.508 -0.9398)
			(stroke
				(width 0)
				(type default)
			)
			(fill no)
			(layer "F.CrtYd")
		)
		(fp_rect
			(start -0.508 0.9398)
			(end 0.508 -0.9398)
			(stroke
				(width 0)
				(type default)
			)
			(fill no)
			(layer "F.Fab")
		)
		(pad "1" smd custom
			(at 0 -0.4445)
			(size 0.1397 0.1397)
			(layers "F.Cu" "F.Mask" "F.Paste")
			(net "P5V_B")
			(options
				(clearance outline)
				(anchor circle)
			)
			(primitives
				(gr_poly
					(pts
						(arc
							(start -0.1778 -0.2794)
							(mid -0.249642 -0.249642)
							(end -0.2794 -0.1778)
						)
						(arc
							(start -0.2794 0.1778)
							(mid -0.249642 0.249642)
							(end -0.1778 0.2794)
						)
						(arc
							(start 0.1778 0.2794)
							(mid 0.249642 0.249642)
							(end 0.2794 0.1778)
						)
						(arc
							(start 0.2794 -0.1778)
							(mid 0.249642 -0.249642)
							(end 0.1778 -0.2794)
						)
					)
					(width 0)
					(fill yes)
				)
			)
		)
		(pad "2" smd custom
			(at 0 0.4445)
			(size 0.1397 0.1397)
			(layers "F.Cu" "F.Mask" "F.Paste")
			(net "USB_EN_2")
			(options
				(clearance outline)
				(anchor circle)
			)
			(primitives
				(gr_poly
					(pts
						(arc
							(start -0.1778 -0.2794)
							(mid -0.249642 -0.249642)
							(end -0.2794 -0.1778)
						)
						(arc
							(start -0.2794 0.1778)
							(mid -0.249642 0.249642)
							(end -0.1778 0.2794)
						)
						(arc
							(start 0.1778 0.2794)
							(mid 0.249642 0.249642)
							(end 0.2794 0.1778)
						)
						(arc
							(start 0.2794 -0.1778)
							(mid 0.249642 -0.249642)
							(end 0.1778 -0.2794)
						)
					)
					(width 0)
					(fill yes)
				)
			)
		)
	)
	(footprint ""
		(layer "F.Cu")
		(at 270.210534 19.450812 -90)
		(property "Reference" "R140"
			(at 0 0 270)
			(layer "F.SilkS")
			(hide yes)
			(effects
				(font
					(size 1.27 1.27)
				)
			)
		)
		(property "Value" "4K7R2F-GP"
			(at 0.064008 -3.993896 270)
			(unlocked yes)
			(layer "F.Fab")
			(hide yes)
			(effects
				(font
					(size 1.016 1.016)
					(thickness 0.1524)
				)
			)
		)
		(property "Device Type" "R402H16"
			(at 0.064008 -5.517896 270)
			(unlocked yes)
			(layer "F.Fab")
			(hide yes)
			(effects
				(font
					(size 1.016 1.016)
					(thickness 0.1524)
				)
			)
		)
		(duplicate_pad_numbers_are_jumpers no)
		(fp_line
			(start -0.508 -0.9398)
			(end -0.508 0.9398)
			(stroke
				(width 0.1524)
				(type default)
			)
			(layer "F.SilkS")
		)
		(fp_line
			(start 0.508 -0.9398)
			(end -0.508 -0.9398)
			(stroke
				(width 0.1524)
				(type default)
			)
			(layer "F.SilkS")
		)
		(fp_rect
			(start -0.508 0.9398)
			(end 0.508 -0.9398)
			(stroke
				(width 0)
				(type default)
			)
			(fill no)
			(layer "F.CrtYd")
		)
		(fp_rect
			(start -0.508 0.9398)
			(end 0.508 -0.9398)
			(stroke
				(width 0)
				(type default)
			)
			(fill no)
			(layer "F.Fab")
		)
		(pad "1" smd custom
			(at 0 -0.4445 270)
			(size 0.1397 0.1397)
			(layers "F.Cu" "F.Mask" "F.Paste")
			(net "P5V_B")
			(options
				(clearance outline)
				(anchor circle)
			)
			(primitives
				(gr_poly
					(pts
						(arc
							(start -0.1778 -0.2794)
							(mid -0.249642 -0.249642)
							(end -0.2794 -0.1778)
						)
						(arc
							(start -0.2794 0.1778)
							(mid -0.249642 0.249642)
							(end -0.1778 0.2794)
						)
						(arc
							(start 0.1778 0.2794)
							(mid 0.249642 0.249642)
							(end 0.2794 0.1778)
						)
						(arc
							(start 0.2794 -0.1778)
							(mid 0.249642 -0.249642)
							(end 0.1778 -0.2794)
						)
					)
					(width 0)
					(fill yes)
				)
			)
		)
		(pad "2" smd custom
			(at 0 0.4445 270)
			(size 0.1397 0.1397)
			(layers "F.Cu" "F.Mask" "F.Paste")
			(net "USB_OCS_N2")
			(options
				(clearance outline)
				(anchor circle)
			)
			(primitives
				(gr_poly
					(pts
						(arc
							(start -0.1778 -0.2794)
							(mid -0.249642 -0.249642)
							(end -0.2794 -0.1778)
						)
						(arc
							(start -0.2794 0.1778)
							(mid -0.249642 0.249642)
							(end -0.1778 0.2794)
						)
						(arc
							(start 0.1778 0.2794)
							(mid 0.249642 0.249642)
							(end 0.2794 0.1778)
						)
						(arc
							(start 0.2794 -0.1778)
							(mid 0.249642 -0.249642)
							(end 0.1778 -0.2794)
						)
					)
					(width 0)
					(fill yes)
				)
			)
		)
	)
	(footprint ""
		(layer "F.Cu")
		(at 243.6876 -242.6716 180)
		(property "Reference" "R84"
			(at 0 0 180)
			(layer "F.SilkS")
			(hide yes)
			(effects
				(font
					(size 1.27 1.27)
				)
			)
		)
		(property "Value" "4K7R2F-GP"
			(at 0.064008 -3.993896 180)
			(unlocked yes)
			(layer "F.Fab")
			(hide yes)
			(effects
				(font
					(size 1.016 1.016)
					(thickness 0.1524)
				)
			)
		)
		(property "Device Type" "R402H16"
			(at 0.064008 -5.517896 180)
			(unlocked yes)
			(layer "F.Fab")
			(hide yes)
			(effects
				(font
					(size 1.016 1.016)
					(thickness 0.1524)
				)
			)
		)
		(duplicate_pad_numbers_are_jumpers no)
		(fp_line
			(start 0.508 -0.9398)
			(end -0.508 -0.9398)
			(stroke
				(width 0.1524)
				(type default)
			)
			(layer "F.SilkS")
		)
		(fp_line
			(start -0.508 -0.9398)
			(end -0.508 0.9398)
			(stroke
				(width 0.1524)
				(type default)
			)
			(layer "F.SilkS")
		)
		(fp_rect
			(start -0.508 0.9398)
			(end 0.508 -0.9398)
			(stroke
				(width 0)
				(type default)
			)
			(fill no)
			(layer "F.CrtYd")
		)
		(fp_rect
			(start -0.508 0.9398)
			(end 0.508 -0.9398)
			(stroke
				(width 0)
				(type default)
			)
			(fill no)
			(layer "F.Fab")
		)
		(pad "1" smd custom
			(at 0 -0.4445 180)
			(size 0.1397 0.1397)
			(layers "F.Cu" "F.Mask" "F.Paste")
			(net "IO_EXP2_A0")
			(options
				(clearance outline)
				(anchor circle)
			)
			(primitives
				(gr_poly
					(pts
						(arc
							(start -0.1778 -0.2794)
							(mid -0.249642 -0.249642)
							(end -0.2794 -0.1778)
						)
						(arc
							(start -0.2794 0.1778)
							(mid -0.249642 0.249642)
							(end -0.1778 0.2794)
						)
						(arc
							(start 0.1778 0.2794)
							(mid 0.249642 0.249642)
							(end 0.2794 0.1778)
						)
						(arc
							(start 0.2794 -0.1778)
							(mid 0.249642 -0.249642)
							(end 0.1778 -0.2794)
						)
					)
					(width 0)
					(fill yes)
				)
			)
		)
		(pad "2" smd custom
			(at 0 0.4445 180)
			(size 0.1397 0.1397)
			(layers "F.Cu" "F.Mask" "F.Paste")
			(net "GND")
			(options
				(clearance outline)
				(anchor circle)
			)
			(primitives
				(gr_poly
					(pts
						(arc
							(start -0.1778 -0.2794)
							(mid -0.249642 -0.249642)
							(end -0.2794 -0.1778)
						)
						(arc
							(start -0.2794 0.1778)
							(mid -0.249642 0.249642)
							(end -0.1778 0.2794)
						)
						(arc
							(start 0.1778 0.2794)
							(mid 0.249642 0.249642)
							(end 0.2794 0.1778)
						)
						(arc
							(start 0.2794 -0.1778)
							(mid 0.249642 -0.249642)
							(end 0.1778 -0.2794)
						)
					)
					(width 0)
					(fill yes)
				)
			)
		)
	)
	(footprint ""
		(layer "F.Cu")
		(at 266.192254 -110.339886 -90)
		(property "Reference" "R992"
			(at 0 0 270)
			(layer "F.SilkS")
			(hide yes)
			(effects
				(font
					(size 1.27 1.27)
				)
			)
		)
		(property "Value" "100KR2F-L1-GP"
			(at 0.064008 -3.993896 270)
			(unlocked yes)
			(layer "F.Fab")
			(hide yes)
			(effects
				(font
					(size 1.016 1.016)
					(thickness 0.1524)
				)
			)
		)
		(property "Device Type" "R402H16"
			(at 0.064008 -5.517896 270)
			(unlocked yes)
			(layer "F.Fab")
			(hide yes)
			(effects
				(font
					(size 1.016 1.016)
					(thickness 0.1524)
				)
			)
		)
		(duplicate_pad_numbers_are_jumpers no)
		(fp_line
			(start -0.508 -0.9398)
			(end -0.508 0.9398)
			(stroke
				(width 0.1524)
				(type default)
			)
			(layer "F.SilkS")
		)
		(fp_line
			(start 0.508 -0.9398)
			(end -0.508 -0.9398)
			(stroke
				(width 0.1524)
				(type default)
			)
			(layer "F.SilkS")
		)
		(fp_rect
			(start -0.508 0.9398)
			(end 0.508 -0.9398)
			(stroke
				(width 0)
				(type default)
			)
			(fill no)
			(layer "F.CrtYd")
		)
		(fp_rect
			(start -0.508 0.9398)
			(end 0.508 -0.9398)
			(stroke
				(width 0)
				(type default)
			)
			(fill no)
			(layer "F.Fab")
		)
		(pad "1" smd custom
			(at 0 -0.4445 270)
			(size 0.1397 0.1397)
			(layers "F.Cu" "F.Mask" "F.Paste")
			(net "PCIE_COMP_B_TO_SCC_B_RST_0")
			(options
				(clearance outline)
				(anchor circle)
			)
			(primitives
				(gr_poly
					(pts
						(arc
							(start -0.1778 -0.2794)
							(mid -0.249642 -0.249642)
							(end -0.2794 -0.1778)
						)
						(arc
							(start -0.2794 0.1778)
							(mid -0.249642 0.249642)
							(end -0.1778 0.2794)
						)
						(arc
							(start 0.1778 0.2794)
							(mid 0.249642 0.249642)
							(end 0.2794 0.1778)
						)
						(arc
							(start 0.2794 -0.1778)
							(mid 0.249642 -0.249642)
							(end 0.1778 -0.2794)
						)
					)
					(width 0)
					(fill yes)
				)
			)
		)
		(pad "2" smd custom
			(at 0 0.4445 270)
			(size 0.1397 0.1397)
			(layers "F.Cu" "F.Mask" "F.Paste")
			(net "GND")
			(options
				(clearance outline)
				(anchor circle)
			)
			(primitives
				(gr_poly
					(pts
						(arc
							(start -0.1778 -0.2794)
							(mid -0.249642 -0.249642)
							(end -0.2794 -0.1778)
						)
						(arc
							(start -0.2794 0.1778)
							(mid -0.249642 0.249642)
							(end -0.1778 0.2794)
						)
						(arc
							(start 0.1778 0.2794)
							(mid 0.249642 0.249642)
							(end 0.2794 0.1778)
						)
						(arc
							(start 0.2794 -0.1778)
							(mid 0.249642 -0.249642)
							(end 0.1778 -0.2794)
						)
					)
					(width 0)
					(fill yes)
				)
			)
		)
	)
	(footprint ""
		(layer "F.Cu")
		(at 98.897948 -61.127894 90)
		(property "Reference" "C384"
			(at 0 0 90)
			(layer "F.SilkS")
			(hide yes)
			(effects
				(font
					(size 1.27 1.27)
				)
			)
		)
		(property "Value" "SCD01U50V2KX-1GP"
			(at 1.1811 -2.7051 90)
			(unlocked yes)
			(layer "F.Fab")
			(hide yes)
			(effects
				(font
					(size 1.016 1.016)
					(thickness 0.1524)
				)
			)
		)
		(property "Device Type" "C402H22"
			(at 1.1811 -4.2291 90)
			(unlocked yes)
			(layer "F.Fab")
			(hide yes)
			(effects
				(font
					(size 1.016 1.016)
					(thickness 0.1524)
				)
			)
		)
		(duplicate_pad_numbers_are_jumpers no)
		(fp_rect
			(start -0.4318 0.9525)
			(end 0.4318 -0.9525)
			(stroke
				(width 0)
				(type default)
			)
			(fill no)
			(layer "F.CrtYd")
		)
		(fp_rect
			(start -0.4318 0.9525)
			(end 0.4318 -0.9525)
			(stroke
				(width 0)
				(type default)
			)
			(fill no)
			(layer "F.Fab")
		)
		(pad "1" smd custom
			(at 0 -0.4445 90)
			(size 0.1524 0.1524)
			(layers "F.Cu" "F.Mask" "F.Paste")
			(net "HDD_PRSNT_26")
			(options
				(clearance outline)
				(anchor circle)
			)
			(primitives
				(gr_poly
					(pts
						(arc
							(start 0.3048 -0.2032)
							(mid 0.275042 -0.275042)
							(end 0.2032 -0.3048)
						)
						(arc
							(start -0.2032 -0.3048)
							(mid -0.275042 -0.275042)
							(end -0.3048 -0.2032)
						)
						(arc
							(start -0.3048 0.2032)
							(mid -0.275042 0.275042)
							(end -0.2032 0.3048)
						)
						(arc
							(start 0.2032 0.3048)
							(mid 0.275042 0.275042)
							(end 0.3048 0.2032)
						)
					)
					(width 0)
					(fill yes)
				)
			)
		)
		(pad "2" smd custom
			(at 0 0.4445 90)
			(size 0.1524 0.1524)
			(layers "F.Cu" "F.Mask" "F.Paste")
			(net "GND")
			(options
				(clearance outline)
				(anchor circle)
			)
			(primitives
				(gr_poly
					(pts
						(arc
							(start 0.3048 -0.2032)
							(mid 0.275042 -0.275042)
							(end 0.2032 -0.3048)
						)
						(arc
							(start -0.2032 -0.3048)
							(mid -0.275042 -0.275042)
							(end -0.3048 -0.2032)
						)
						(arc
							(start -0.3048 0.2032)
							(mid -0.275042 0.275042)
							(end -0.2032 0.3048)
						)
						(arc
							(start 0.2032 0.3048)
							(mid 0.275042 0.275042)
							(end 0.3048 0.2032)
						)
					)
					(width 0)
					(fill yes)
				)
			)
		)
	)
	(footprint ""
		(layer "F.Cu")
		(at 227.67671 -385.646168)
		(property "Reference" "R1131"
			(at 0 0 0)
			(layer "F.SilkS")
			(hide yes)
			(effects
				(font
					(size 1.27 1.27)
				)
			)
		)
		(property "Value" "3K83R2F-GP"
			(at 0.064008 -3.993896 0)
			(unlocked yes)
			(layer "F.Fab")
			(hide yes)
			(effects
				(font
					(size 1.016 1.016)
					(thickness 0.1524)
				)
			)
		)
		(property "Device Type" "R402H16"
			(at 0.064008 -5.517896 0)
			(unlocked yes)
			(layer "F.Fab")
			(hide yes)
			(effects
				(font
					(size 1.016 1.016)
					(thickness 0.1524)
				)
			)
		)
		(duplicate_pad_numbers_are_jumpers no)
		(fp_line
			(start -0.508 -0.9398)
			(end -0.508 0.9398)
			(stroke
				(width 0.1524)
				(type default)
			)
			(layer "F.SilkS")
		)
		(fp_line
			(start 0.508 -0.9398)
			(end -0.508 -0.9398)
			(stroke
				(width 0.1524)
				(type default)
			)
			(layer "F.SilkS")
		)
		(fp_rect
			(start -0.508 0.9398)
			(end 0.508 -0.9398)
			(stroke
				(width 0)
				(type default)
			)
			(fill no)
			(layer "F.CrtYd")
		)
		(fp_rect
			(start -0.508 0.9398)
			(end 0.508 -0.9398)
			(stroke
				(width 0)
				(type default)
			)
			(fill no)
			(layer "F.Fab")
		)
		(pad "1" smd custom
			(at 0 -0.4445)
			(size 0.1397 0.1397)
			(layers "F.Cu" "F.Mask" "F.Paste")
			(net "DPB_PWR_BTN_BUF_A")
			(options
				(clearance outline)
				(anchor circle)
			)
			(primitives
				(gr_poly
					(pts
						(arc
							(start -0.1778 -0.2794)
							(mid -0.249642 -0.249642)
							(end -0.2794 -0.1778)
						)
						(arc
							(start -0.2794 0.1778)
							(mid -0.249642 0.249642)
							(end -0.1778 0.2794)
						)
						(arc
							(start 0.1778 0.2794)
							(mid 0.249642 0.249642)
							(end 0.2794 0.1778)
						)
						(arc
							(start 0.2794 -0.1778)
							(mid 0.249642 -0.249642)
							(end 0.1778 -0.2794)
						)
					)
					(width 0)
					(fill yes)
				)
			)
		)
		(pad "2" smd custom
			(at 0 0.4445)
			(size 0.1397 0.1397)
			(layers "F.Cu" "F.Mask" "F.Paste")
			(net "GND")
			(options
				(clearance outline)
				(anchor circle)
			)
			(primitives
				(gr_poly
					(pts
						(arc
							(start -0.1778 -0.2794)
							(mid -0.249642 -0.249642)
							(end -0.2794 -0.1778)
						)
						(arc
							(start -0.2794 0.1778)
							(mid -0.249642 0.249642)
							(end -0.1778 0.2794)
						)
						(arc
							(start 0.1778 0.2794)
							(mid 0.249642 0.249642)
							(end 0.2794 0.1778)
						)
						(arc
							(start 0.2794 -0.1778)
							(mid 0.249642 -0.249642)
							(end 0.1778 -0.2794)
						)
					)
					(width 0)
					(fill yes)
				)
			)
		)
	)
	(footprint ""
		(layer "F.Cu")
		(at 449.291202 -257.48615 -90)
		(property "Reference" "R1246"
			(at 0 0 270)
			(layer "F.SilkS")
			(hide yes)
			(effects
				(font
					(size 1.27 1.27)
				)
			)
		)
		(property "Value" "10KR2F-2-GP"
			(at 0.064008 -3.993896 270)
			(unlocked yes)
			(layer "F.Fab")
			(hide yes)
			(effects
				(font
					(size 1.016 1.016)
					(thickness 0.1524)
				)
			)
		)
		(property "Device Type" "R402H16"
			(at 0.064008 -5.517896 270)
			(unlocked yes)
			(layer "F.Fab")
			(hide yes)
			(effects
				(font
					(size 1.016 1.016)
					(thickness 0.1524)
				)
			)
		)
		(duplicate_pad_numbers_are_jumpers no)
		(fp_line
			(start -0.508 -0.9398)
			(end -0.508 0.9398)
			(stroke
				(width 0.1524)
				(type default)
			)
			(layer "F.SilkS")
		)
		(fp_line
			(start 0.508 -0.9398)
			(end -0.508 -0.9398)
			(stroke
				(width 0.1524)
				(type default)
			)
			(layer "F.SilkS")
		)
		(fp_rect
			(start -0.508 0.9398)
			(end 0.508 -0.9398)
			(stroke
				(width 0)
				(type default)
			)
			(fill no)
			(layer "F.CrtYd")
		)
		(fp_rect
			(start -0.508 0.9398)
			(end 0.508 -0.9398)
			(stroke
				(width 0)
				(type default)
			)
			(fill no)
			(layer "F.Fab")
		)
		(pad "1" smd custom
			(at 0 -0.4445 270)
			(size 0.1397 0.1397)
			(layers "F.Cu" "F.Mask" "F.Paste")
			(net "P5V_C_EN_R")
			(options
				(clearance outline)
				(anchor circle)
			)
			(primitives
				(gr_poly
					(pts
						(arc
							(start -0.1778 -0.2794)
							(mid -0.249642 -0.249642)
							(end -0.2794 -0.1778)
						)
						(arc
							(start -0.2794 0.1778)
							(mid -0.249642 0.249642)
							(end -0.1778 0.2794)
						)
						(arc
							(start 0.1778 0.2794)
							(mid 0.249642 0.249642)
							(end 0.2794 0.1778)
						)
						(arc
							(start 0.2794 -0.1778)
							(mid 0.249642 -0.249642)
							(end 0.1778 -0.2794)
						)
					)
					(width 0)
					(fill yes)
				)
			)
		)
		(pad "2" smd custom
			(at 0 0.4445 270)
			(size 0.1397 0.1397)
			(layers "F.Cu" "F.Mask" "F.Paste")
			(net "GND")
			(options
				(clearance outline)
				(anchor circle)
			)
			(primitives
				(gr_poly
					(pts
						(arc
							(start -0.1778 -0.2794)
							(mid -0.249642 -0.249642)
							(end -0.2794 -0.1778)
						)
						(arc
							(start -0.2794 0.1778)
							(mid -0.249642 0.249642)
							(end -0.1778 0.2794)
						)
						(arc
							(start 0.1778 0.2794)
							(mid 0.249642 0.249642)
							(end 0.2794 0.1778)
						)
						(arc
							(start 0.2794 -0.1778)
							(mid 0.249642 -0.249642)
							(end 0.1778 -0.2794)
						)
					)
					(width 0)
					(fill yes)
				)
			)
		)
	)
)
